(kicad_pcb
	(version 20260206)
	(generator "pcbnew")
	(generator_version "10.0")
	(general
		(thickness 1.6)
		(legacy_teardrops no)
	)
	(paper "A4")
	(title_block
		(title "12092022_DA0F0TFB6D0_F0T_FAN_BOARD_MP5048_D_brd_v02_OCP.brd")
		(comment 1 "Grand Teton / footprints 845-850 of 924")
	)
	(layers
		(0 "F.Cu" signal "TOP")
		(4 "In1.Cu" signal "GND")
		(6 "In2.Cu" signal "IN1")
		(8 "In3.Cu" signal "IN2")
		(10 "In4.Cu" signal "GND1")
		(2 "B.Cu" signal "BOTTOM")
		(9 "F.Adhes" user "F.Adhesive")
		(11 "B.Adhes" user "B.Adhesive")
		(13 "F.Paste" user "Package Geometry/Pastemask Top")
		(15 "B.Paste" user "Package Geometry/Pastemask Bottom")
		(5 "F.SilkS" user "Ref Des/Silkscreen Top")
		(7 "B.SilkS" user "Ref Des/Silkscreen Bottom")
		(1 "F.Mask" user "Board Geometry/Soldermask Top")
		(3 "B.Mask" user "Board Geometry/Soldermask Bottom")
		(17 "Dwgs.User" user "User.Drawings")
		(19 "Cmts.User" user "User.Comments")
		(21 "Eco1.User" user "User.Eco1")
		(23 "Eco2.User" user "User.Eco2")
		(25 "Edge.Cuts" user "Board Geometry/Outline")
		(27 "Margin" user)
		(31 "F.CrtYd" user "Package Geometry/Place Bound Top")
		(29 "B.CrtYd" user "Package Geometry/Place Bound Bottom")
		(35 "F.Fab" user "Ref Des/Assembly Top")
		(33 "B.Fab" user "Ref Des/Assembly Bottom")
	)
	(footprint ""
		(layer "B.Cu")
		(at 19.573494 -73.971912 90)
		(property "Reference" "PR58"
			(at 0 0 90)
			(layer "B.SilkS")
			(hide yes)
			(effects
				(font
					(size 1.27 1.27)
				)
				(justify mirror)
			)
		)
		(property "Value" ""
			(at 0 0 90)
			(layer "B.Fab")
			(effects
				(font
					(size 1.27 1.27)
				)
				(justify mirror)
			)
		)
		(duplicate_pad_numbers_are_jumpers no)
		(fp_line
			(start 0.7874 -0.4064)
			(end -0.7874 -0.4064)
			(stroke
				(width 0.1524)
				(type default)
			)
			(layer "B.SilkS")
		)
		(fp_line
			(start -0.7874 -0.4064)
			(end -0.7874 0.4064)
			(stroke
				(width 0.1524)
				(type default)
			)
			(layer "B.SilkS")
		)
		(fp_line
			(start 0.7874 0.4064)
			(end 0.7874 -0.4064)
			(stroke
				(width 0.1524)
				(type default)
			)
			(layer "B.SilkS")
		)
		(fp_line
			(start -0.7874 0.4064)
			(end 0.7874 0.4064)
			(stroke
				(width 0.1524)
				(type default)
			)
			(layer "B.SilkS")
		)
		(fp_line
			(start 0.67945 -0.305054)
			(end 0.12065 -0.305054)
			(stroke
				(width 0.1)
				(type default)
			)
			(layer "B.Fab")
		)
		(fp_line
			(start 0.12065 -0.305054)
			(end 0.12065 -0.2794)
			(stroke
				(width 0.1)
				(type default)
			)
			(layer "B.Fab")
		)
		(fp_line
			(start -0.12065 -0.3048)
			(end -0.67945 -0.3048)
			(stroke
				(width 0.1)
				(type default)
			)
			(layer "B.Fab")
		)
		(fp_line
			(start -0.67945 -0.3048)
			(end -0.67945 0.3048)
			(stroke
				(width 0.1)
				(type default)
			)
			(layer "B.Fab")
		)
		(fp_line
			(start 0.12065 -0.2794)
			(end -0.12065 -0.2794)
			(stroke
				(width 0.1)
				(type default)
			)
			(layer "B.Fab")
		)
		(fp_line
			(start -0.12065 -0.2794)
			(end -0.12065 -0.3048)
			(stroke
				(width 0.1)
				(type default)
			)
			(layer "B.Fab")
		)
		(fp_line
			(start 0.12065 0.2794)
			(end 0.12065 0.3048)
			(stroke
				(width 0.1)
				(type default)
			)
			(layer "B.Fab")
		)
		(fp_line
			(start -0.120396 0.2794)
			(end 0.12065 0.2794)
			(stroke
				(width 0.1)
				(type default)
			)
			(layer "B.Fab")
		)
		(fp_line
			(start 0.67945 0.3048)
			(end 0.67945 -0.305054)
			(stroke
				(width 0.1)
				(type default)
			)
			(layer "B.Fab")
		)
		(fp_line
			(start 0.12065 0.3048)
			(end 0.67945 0.3048)
			(stroke
				(width 0.1)
				(type default)
			)
			(layer "B.Fab")
		)
		(fp_line
			(start -0.120396 0.3048)
			(end -0.120396 0.2794)
			(stroke
				(width 0.1)
				(type default)
			)
			(layer "B.Fab")
		)
		(fp_line
			(start -0.67945 0.3048)
			(end -0.120396 0.3048)
			(stroke
				(width 0.1)
				(type default)
			)
			(layer "B.Fab")
		)
		(pad "1" smd rect
			(at 0.40005 0 90)
			(size 0.4572 0.508)
			(layers "B.Cu" "B.Mask" "B.Paste")
			(net "FAN_5_CS")
		)
		(pad "2" smd rect
			(at -0.40005 0 90)
			(size 0.4572 0.508)
			(layers "B.Cu" "B.Mask" "B.Paste")
			(net "GND")
		)
	)
	(footprint ""
		(layer "B.Cu")
		(at 39.968932 -71.304912)
		(property "Reference" "U381"
			(at -3.392932 -0.677418 0)
			(unlocked yes)
			(layer "B.SilkS")
			(effects
				(font
					(size 0.7874 0.5842)
					(thickness 0.1524)
				)
				(justify mirror)
			)
		)
		(property "Value" ""
			(at 0 0 0)
			(layer "B.Fab")
			(effects
				(font
					(size 1.27 1.27)
				)
				(justify mirror)
			)
		)
		(duplicate_pad_numbers_are_jumpers no)
		(fp_line
			(start -1.7018 -1.1176)
			(end -1.7018 1.1176)
			(stroke
				(width 0.1524)
				(type default)
			)
			(layer "B.SilkS")
		)
		(fp_line
			(start -1.7018 -1.1176)
			(end -0.254 -1.1176)
			(stroke
				(width 0.1524)
				(type default)
			)
			(layer "B.SilkS")
		)
		(fp_line
			(start -1.7018 1.1176)
			(end 1.7018 1.1176)
			(stroke
				(width 0.1524)
				(type default)
			)
			(layer "B.SilkS")
		)
		(fp_line
			(start -0.254 -1.1176)
			(end 0 -0.7112)
			(stroke
				(width 0.1524)
				(type default)
			)
			(layer "B.SilkS")
		)
		(fp_line
			(start 0 -0.7112)
			(end 0.254 -1.1176)
			(stroke
				(width 0.1524)
				(type default)
			)
			(layer "B.SilkS")
		)
		(fp_line
			(start 0.254 -1.1176)
			(end 1.7018 -1.1176)
			(stroke
				(width 0.1524)
				(type default)
			)
			(layer "B.SilkS")
		)
		(fp_line
			(start 1.7018 1.1176)
			(end 1.7018 -1.1176)
			(stroke
				(width 0.1524)
				(type default)
			)
			(layer "B.SilkS")
		)
		(fp_poly
			(pts
				(xy 1.8161 -0.675386) (xy 2.4003 -0.446786) (xy 2.4003 -0.878586)
			)
			(stroke
				(width 0)
				(type default)
			)
			(fill yes)
			(layer "B.SilkS")
		)
		(fp_line
			(start -1.5494 -1.1176)
			(end -1.5494 1.1176)
			(stroke
				(width 0.1)
				(type default)
			)
			(layer "B.Fab")
		)
		(fp_line
			(start -1.5494 -1.1176)
			(end -0.254 -1.1176)
			(stroke
				(width 0.1)
				(type default)
			)
			(layer "B.Fab")
		)
		(fp_line
			(start -1.5494 1.1176)
			(end 1.5494 1.1176)
			(stroke
				(width 0.1)
				(type default)
			)
			(layer "B.Fab")
		)
		(fp_line
			(start -0.254 -1.1176)
			(end 0.254 -1.1176)
			(stroke
				(width 0.1)
				(type default)
			)
			(layer "B.Fab")
		)
		(fp_line
			(start 0.254 -1.1176)
			(end 1.5494 -1.1176)
			(stroke
				(width 0.1)
				(type default)
			)
			(layer "B.Fab")
		)
		(fp_line
			(start 1.5494 1.1176)
			(end 1.5494 -1.1176)
			(stroke
				(width 0.1)
				(type default)
			)
			(layer "B.Fab")
		)
		(fp_poly
			(pts
				(xy 1.8161 -0.675386) (xy 2.4003 -0.446786) (xy 2.4003 -0.878586)
			)
			(stroke
				(width 0)
				(type default)
			)
			(fill yes)
			(layer "B.Fab")
		)
		(pad "1" smd rect
			(at 0.962406 -0.649986 270)
			(size 0.3302 1.1684)
			(layers "B.Cu" "B.Mask" "B.Paste")
			(net "FAN_2_PRESENT_R")
		)
		(pad "2" smd rect
			(at 0.962406 0 270)
			(size 0.3302 1.1684)
			(layers "B.Cu" "B.Mask" "B.Paste")
			(net "P52V_FAN_2_BUFF_EN_R")
		)
		(pad "3" smd rect
			(at 0.962406 0.649986 270)
			(size 0.3302 1.1684)
			(layers "B.Cu" "B.Mask" "B.Paste")
			(net "GND")
		)
		(pad "4" smd rect
			(at -0.962406 0.649986 270)
			(size 0.3302 1.1684)
			(layers "B.Cu" "B.Mask" "B.Paste")
			(net "P52V_FAN_2_EN")
		)
		(pad "5" smd rect
			(at -0.962406 -0.649986 270)
			(size 0.3302 1.1684)
			(layers "B.Cu" "B.Mask" "B.Paste")
			(net "P3V3_AUX")
		)
	)
	(footprint ""
		(layer "B.Cu")
		(at 17.653 -134.239 180)
		(property "Reference" "R5441"
			(at 0 0 0)
			(layer "B.SilkS")
			(hide yes)
			(effects
				(font
					(size 1.27 1.27)
				)
				(justify mirror)
			)
		)
		(property "Value" ""
			(at 0 0 0)
			(layer "B.Fab")
			(effects
				(font
					(size 1.27 1.27)
				)
				(justify mirror)
			)
		)
		(duplicate_pad_numbers_are_jumpers no)
		(fp_line
			(start 0.7874 0.4064)
			(end 0.7874 -0.4064)
			(stroke
				(width 0.1524)
				(type default)
			)
			(layer "B.SilkS")
		)
		(fp_line
			(start 0.7874 -0.4064)
			(end -0.7874 -0.4064)
			(stroke
				(width 0.1524)
				(type default)
			)
			(layer "B.SilkS")
		)
		(fp_line
			(start -0.7874 0.4064)
			(end 0.7874 0.4064)
			(stroke
				(width 0.1524)
				(type default)
			)
			(layer "B.SilkS")
		)
		(fp_line
			(start -0.7874 -0.4064)
			(end -0.7874 0.4064)
			(stroke
				(width 0.1524)
				(type default)
			)
			(layer "B.SilkS")
		)
		(fp_line
			(start 0.67945 0.3048)
			(end 0.67945 -0.305054)
			(stroke
				(width 0.1)
				(type default)
			)
			(layer "B.Fab")
		)
		(fp_line
			(start 0.67945 -0.305054)
			(end 0.12065 -0.305054)
			(stroke
				(width 0.1)
				(type default)
			)
			(layer "B.Fab")
		)
		(fp_line
			(start 0.12065 0.3048)
			(end 0.67945 0.3048)
			(stroke
				(width 0.1)
				(type default)
			)
			(layer "B.Fab")
		)
		(fp_line
			(start 0.12065 0.2794)
			(end 0.12065 0.3048)
			(stroke
				(width 0.1)
				(type default)
			)
			(layer "B.Fab")
		)
		(fp_line
			(start 0.12065 -0.2794)
			(end -0.12065 -0.2794)
			(stroke
				(width 0.1)
				(type default)
			)
			(layer "B.Fab")
		)
		(fp_line
			(start 0.12065 -0.305054)
			(end 0.12065 -0.2794)
			(stroke
				(width 0.1)
				(type default)
			)
			(layer "B.Fab")
		)
		(fp_line
			(start -0.120396 0.3048)
			(end -0.120396 0.2794)
			(stroke
				(width 0.1)
				(type default)
			)
			(layer "B.Fab")
		)
		(fp_line
			(start -0.120396 0.2794)
			(end 0.12065 0.2794)
			(stroke
				(width 0.1)
				(type default)
			)
			(layer "B.Fab")
		)
		(fp_line
			(start -0.12065 -0.2794)
			(end -0.12065 -0.3048)
			(stroke
				(width 0.1)
				(type default)
			)
			(layer "B.Fab")
		)
		(fp_line
			(start -0.12065 -0.3048)
			(end -0.67945 -0.3048)
			(stroke
				(width 0.1)
				(type default)
			)
			(layer "B.Fab")
		)
		(fp_line
			(start -0.67945 0.3048)
			(end -0.120396 0.3048)
			(stroke
				(width 0.1)
				(type default)
			)
			(layer "B.Fab")
		)
		(fp_line
			(start -0.67945 -0.3048)
			(end -0.67945 0.3048)
			(stroke
				(width 0.1)
				(type default)
			)
			(layer "B.Fab")
		)
		(pad "1" smd rect
			(at 0.40005 0 180)
			(size 0.4572 0.508)
			(layers "B.Cu" "B.Mask" "B.Paste")
			(net "FAN_7_TACH_OL")
		)
		(pad "2" smd rect
			(at -0.40005 0 180)
			(size 0.4572 0.508)
			(layers "B.Cu" "B.Mask" "B.Paste")
			(net "GND")
		)
	)
	(footprint ""
		(layer "B.Cu")
		(at 14.351 -258.572 -90)
		(property "Reference" "PC3125"
			(at 0 0 90)
			(layer "B.SilkS")
			(hide yes)
			(effects
				(font
					(size 1.27 1.27)
				)
				(justify mirror)
			)
		)
		(property "Value" ""
			(at 0 0 90)
			(layer "B.Fab")
			(effects
				(font
					(size 1.27 1.27)
				)
				(justify mirror)
			)
		)
		(duplicate_pad_numbers_are_jumpers no)
		(fp_line
			(start -0.7874 0.4064)
			(end 0.7874 0.4064)
			(stroke
				(width 0.1524)
				(type default)
			)
			(layer "B.SilkS")
		)
		(fp_line
			(start 0.7874 0.4064)
			(end 0.7874 -0.4064)
			(stroke
				(width 0.1524)
				(type default)
			)
			(layer "B.SilkS")
		)
		(fp_line
			(start -0.7874 -0.4064)
			(end -0.7874 0.4064)
			(stroke
				(width 0.1524)
				(type default)
			)
			(layer "B.SilkS")
		)
		(fp_line
			(start 0.7874 -0.4064)
			(end -0.7874 -0.4064)
			(stroke
				(width 0.1524)
				(type default)
			)
			(layer "B.SilkS")
		)
		(fp_line
			(start -0.67945 0.3048)
			(end -0.120396 0.3048)
			(stroke
				(width 0.1)
				(type default)
			)
			(layer "B.Fab")
		)
		(fp_line
			(start -0.120396 0.3048)
			(end -0.120396 0.2794)
			(stroke
				(width 0.1)
				(type default)
			)
			(layer "B.Fab")
		)
		(fp_line
			(start 0.12065 0.3048)
			(end 0.67945 0.3048)
			(stroke
				(width 0.1)
				(type default)
			)
			(layer "B.Fab")
		)
		(fp_line
			(start 0.67945 0.3048)
			(end 0.67945 -0.305054)
			(stroke
				(width 0.1)
				(type default)
			)
			(layer "B.Fab")
		)
		(fp_line
			(start -0.120396 0.2794)
			(end 0.12065 0.2794)
			(stroke
				(width 0.1)
				(type default)
			)
			(layer "B.Fab")
		)
		(fp_line
			(start 0.12065 0.2794)
			(end 0.12065 0.3048)
			(stroke
				(width 0.1)
				(type default)
			)
			(layer "B.Fab")
		)
		(fp_line
			(start -0.12065 -0.2794)
			(end -0.12065 -0.3048)
			(stroke
				(width 0.1)
				(type default)
			)
			(layer "B.Fab")
		)
		(fp_line
			(start 0.12065 -0.2794)
			(end -0.12065 -0.2794)
			(stroke
				(width 0.1)
				(type default)
			)
			(layer "B.Fab")
		)
		(fp_line
			(start -0.67945 -0.3048)
			(end -0.67945 0.3048)
			(stroke
				(width 0.1)
				(type default)
			)
			(layer "B.Fab")
		)
		(fp_line
			(start -0.12065 -0.3048)
			(end -0.67945 -0.3048)
			(stroke
				(width 0.1)
				(type default)
			)
			(layer "B.Fab")
		)
		(fp_line
			(start 0.12065 -0.305054)
			(end 0.12065 -0.2794)
			(stroke
				(width 0.1)
				(type default)
			)
			(layer "B.Fab")
		)
		(fp_line
			(start 0.67945 -0.305054)
			(end 0.12065 -0.305054)
			(stroke
				(width 0.1)
				(type default)
			)
			(layer "B.Fab")
		)
		(pad "1" smd circle
			(at 0.40005 0 90)
			(size 0 0)
			(layers "B.Cu" "B.Mask" "B.Paste")
			(net "GND")
		)
		(pad "2" smd circle
			(at -0.40005 0 90)
			(size 0 0)
			(layers "B.Cu" "B.Mask" "B.Paste")
			(net "FAN_7_CLREF")
		)
	)
	(footprint ""
		(layer "B.Cu")
		(at 42.229532 -246.163846 -90)
		(property "Reference" "PC9"
			(at 0 0 90)
			(layer "B.SilkS")
			(hide yes)
			(effects
				(font
					(size 1.27 1.27)
				)
				(justify mirror)
			)
		)
		(property "Value" ""
			(at 0 0 90)
			(layer "B.Fab")
			(effects
				(font
					(size 1.27 1.27)
				)
				(justify mirror)
			)
		)
		(duplicate_pad_numbers_are_jumpers no)
		(fp_line
			(start -1.524 0.762)
			(end 1.524 0.762)
			(stroke
				(width 0.1524)
				(type default)
			)
			(layer "B.SilkS")
		)
		(fp_line
			(start 1.524 0.762)
			(end 1.524 -0.762)
			(stroke
				(width 0.1524)
				(type default)
			)
			(layer "B.SilkS")
		)
		(fp_line
			(start -1.524 -0.762)
			(end -1.524 0.762)
			(stroke
				(width 0.1524)
				(type default)
			)
			(layer "B.SilkS")
		)
		(fp_line
			(start 1.524 -0.762)
			(end -1.524 -0.762)
			(stroke
				(width 0.1524)
				(type default)
			)
			(layer "B.SilkS")
		)
		(fp_line
			(start -1.1049 0.724916)
			(end -1.1049 -0.724916)
			(stroke
				(width 0.1)
				(type default)
			)
			(layer "B.Fab")
		)
		(fp_line
			(start 1.1049 0.724916)
			(end -1.1049 0.724916)
			(stroke
				(width 0.1)
				(type default)
			)
			(layer "B.Fab")
		)
		(fp_line
			(start -1.1049 -0.724916)
			(end 1.1049 -0.724916)
			(stroke
				(width 0.1)
				(type default)
			)
			(layer "B.Fab")
		)
		(fp_line
			(start 1.1049 -0.724916)
			(end 1.1049 0.724916)
			(stroke
				(width 0.1)
				(type default)
			)
			(layer "B.Fab")
		)
		(pad "1" smd rect
			(at 0.889 0 270)
			(size 1.016 1.27)
			(layers "B.Cu" "B.Mask" "B.Paste")
			(net "P52V_HSC")
		)
		(pad "2" smd rect
			(at -0.889 0 270)
			(size 1.016 1.27)
			(layers "B.Cu" "B.Mask" "B.Paste")
			(net "GND")
		)
	)
	(footprint ""
		(layer "B.Cu")
		(at 40.894 -126.619 180)
		(property "Reference" "R5433"
			(at 0 0 0)
			(layer "B.SilkS")
			(hide yes)
			(effects
				(font
					(size 1.27 1.27)
				)
				(justify mirror)
			)
		)
		(property "Value" ""
			(at 0 0 0)
			(layer "B.Fab")
			(effects
				(font
					(size 1.27 1.27)
				)
				(justify mirror)
			)
		)
		(duplicate_pad_numbers_are_jumpers no)
		(fp_line
			(start 0.7874 0.4064)
			(end 0.7874 -0.4064)
			(stroke
				(width 0.1524)
				(type default)
			)
			(layer "B.SilkS")
		)
		(fp_line
			(start 0.7874 -0.4064)
			(end -0.7874 -0.4064)
			(stroke
				(width 0.1524)
				(type default)
			)
			(layer "B.SilkS")
		)
		(fp_line
			(start -0.7874 0.4064)
			(end 0.7874 0.4064)
			(stroke
				(width 0.1524)
				(type default)
			)
			(layer "B.SilkS")
		)
		(fp_line
			(start -0.7874 -0.4064)
			(end -0.7874 0.4064)
			(stroke
				(width 0.1524)
				(type default)
			)
			(layer "B.SilkS")
		)
		(fp_line
			(start 0.67945 0.3048)
			(end 0.67945 -0.305054)
			(stroke
				(width 0.1)
				(type default)
			)
			(layer "B.Fab")
		)
		(fp_line
			(start 0.67945 -0.305054)
			(end 0.12065 -0.305054)
			(stroke
				(width 0.1)
				(type default)
			)
			(layer "B.Fab")
		)
		(fp_line
			(start 0.12065 0.3048)
			(end 0.67945 0.3048)
			(stroke
				(width 0.1)
				(type default)
			)
			(layer "B.Fab")
		)
		(fp_line
			(start 0.12065 0.2794)
			(end 0.12065 0.3048)
			(stroke
				(width 0.1)
				(type default)
			)
			(layer "B.Fab")
		)
		(fp_line
			(start 0.12065 -0.2794)
			(end -0.12065 -0.2794)
			(stroke
				(width 0.1)
				(type default)
			)
			(layer "B.Fab")
		)
		(fp_line
			(start 0.12065 -0.305054)
			(end 0.12065 -0.2794)
			(stroke
				(width 0.1)
				(type default)
			)
			(layer "B.Fab")
		)
		(fp_line
			(start -0.120396 0.3048)
			(end -0.120396 0.2794)
			(stroke
				(width 0.1)
				(type default)
			)
			(layer "B.Fab")
		)
		(fp_line
			(start -0.120396 0.2794)
			(end 0.12065 0.2794)
			(stroke
				(width 0.1)
				(type default)
			)
			(layer "B.Fab")
		)
		(fp_line
			(start -0.12065 -0.2794)
			(end -0.12065 -0.3048)
			(stroke
				(width 0.1)
				(type default)
			)
			(layer "B.Fab")
		)
		(fp_line
			(start -0.12065 -0.3048)
			(end -0.67945 -0.3048)
			(stroke
				(width 0.1)
				(type default)
			)
			(layer "B.Fab")
		)
		(fp_line
			(start -0.67945 0.3048)
			(end -0.120396 0.3048)
			(stroke
				(width 0.1)
				(type default)
			)
			(layer "B.Fab")
		)
		(fp_line
			(start -0.67945 -0.3048)
			(end -0.67945 0.3048)
			(stroke
				(width 0.1)
				(type default)
			)
			(layer "B.Fab")
		)
		(pad "1" smd rect
			(at 0.40005 0 180)
			(size 0.4572 0.508)
			(layers "B.Cu" "B.Mask" "B.Paste")
			(net "FAN_3_TACH_OL")
		)
		(pad "2" smd rect
			(at -0.40005 0 180)
			(size 0.4572 0.508)
			(layers "B.Cu" "B.Mask" "B.Paste")
			(net "GND")
		)
	)
)
